(kicad_pcb
	(version 20260206)
	(generator "pcbnew")
	(generator_version "10.0")
	(general
		(thickness 1.6)
		(legacy_teardrops no)
	)
	(paper "A4")
	(title_block
		(title "01162023_DA0F0TEBIF0_F0T_Expander_BD_F_brd_V02_OCP.brd")
		(comment 1 "Grand Teton / footprints 2042-2045 of 9728")
	)
	(layers
		(0 "F.Cu" signal "TOP")
		(4 "In1.Cu" signal "GND")
		(6 "In2.Cu" signal "VCC")
		(8 "In3.Cu" signal "VCC1")
		(10 "In4.Cu" signal "GND1")
		(12 "In5.Cu" signal "IN1")
		(14 "In6.Cu" signal "GND2")
		(16 "In7.Cu" signal "IN2")
		(18 "In8.Cu" signal "GND3")
		(20 "In9.Cu" signal "IN3")
		(22 "In10.Cu" signal "GND4")
		(24 "In11.Cu" signal "IN4")
		(26 "In12.Cu" signal "GND5")
		(28 "In13.Cu" signal "IN5")
		(30 "In14.Cu" signal "GND6")
		(32 "In15.Cu" signal "IN6")
		(34 "In16.Cu" signal "GND7")
		(2 "B.Cu" signal "BOTTOM")
		(9 "F.Adhes" user "F.Adhesive")
		(11 "B.Adhes" user "B.Adhesive")
		(13 "F.Paste" user "Package Geometry/Pastemask Top")
		(15 "B.Paste" user "Package Geometry/Pastemask Bottom")
		(5 "F.SilkS" user "Ref Des/Silkscreen Top")
		(7 "B.SilkS" user "Ref Des/Silkscreen Bottom")
		(1 "F.Mask" user "Board Geometry/Soldermask Top")
		(3 "B.Mask" user "Board Geometry/Soldermask Bottom")
		(17 "Dwgs.User" user "User.Drawings")
		(19 "Cmts.User" user "User.Comments")
		(21 "Eco1.User" user "User.Eco1")
		(23 "Eco2.User" user "User.Eco2")
		(25 "Edge.Cuts" user "Board Geometry/Outline")
		(27 "Margin" user)
		(31 "F.CrtYd" user "Package Geometry/Place Bound Top")
		(29 "B.CrtYd" user "Package Geometry/Place Bound Bottom")
		(35 "F.Fab" user "Ref Des/Assembly Top")
		(33 "B.Fab" user "Ref Des/Assembly Bottom")
	)
	(footprint ""
		(layer "F.Cu")
		(at 377.949714 -270.89989)
		(property "Reference" "H97"
			(at -8.582152 5.53339 0)
			(unlocked yes)
			(layer "F.SilkS")
			(effects
				(font
					(size 0.7874 0.5842)
					(thickness 0.1524)
				)
				(justify left)
			)
		)
		(property "Value" ""
			(at 0 0 0)
			(layer "F.Fab")
			(effects
				(font
					(size 1.27 1.27)
				)
			)
		)
		(duplicate_pad_numbers_are_jumpers no)
		(fp_arc
			(start -6.13156 -5.138166)
			(mid -0.38317 -7.990754)
			(end 5.611876 -5.701538)
			(stroke
				(width 0.1524)
				(type default)
			)
			(layer "F.SilkS")
		)
		(fp_arc
			(start 7.957058 -0.828294)
			(mid 7.989266 -0.414704)
			(end 7.999984 0)
			(stroke
				(width 0.1524)
				(type default)
			)
			(layer "F.SilkS")
		)
		(fp_arc
			(start 7.999984 0)
			(mid -1.072494 7.927345)
			(end -7.711948 -2.12598)
			(stroke
				(width 0.1524)
				(type default)
			)
			(layer "F.SilkS")
		)
		(fp_arc
			(start -5.678932 -5.634482)
			(mid -4.30144 -6.745127)
			(end -2.713482 -7.525766)
			(stroke
				(width 0.1524)
				(type default)
			)
			(layer "B.SilkS")
		)
		(fp_arc
			(start 1.398016 -7.877048)
			(mid 3.669224 -7.10905)
			(end 5.61086 -5.702554)
			(stroke
				(width 0.1524)
				(type default)
			)
			(layer "B.SilkS")
		)
		(fp_arc
			(start 7.933182 -1.032256)
			(mid 7.983281 -0.517209)
			(end 7.999984 0)
			(stroke
				(width 0.1524)
				(type default)
			)
			(layer "B.SilkS")
		)
		(fp_arc
			(start 7.999984 0)
			(mid 0.652631 7.97313)
			(end -7.893304 1.300734)
			(stroke
				(width 0.1524)
				(type default)
			)
			(layer "B.SilkS")
		)
		(fp_circle
			(center 0 0)
			(end 7.999984 0)
			(stroke
				(width 0.1)
				(type default)
			)
			(fill no)
			(layer "B.Fab")
		)
		(fp_circle
			(center 0 0)
			(end 7.999984 0)
			(stroke
				(width 0.1)
				(type default)
			)
			(fill no)
			(layer "F.Fab")
		)
		(pad "" np_thru_hole circle
			(at 0 0)
			(size 4.5212 4.5212)
			(drill 4.5212)
			(layers "*.Cu" "*.Mask")
			(clearance 0.381)
			(thermal_gap 0.381)
		)
		(pad "2" thru_hole circle
			(at 3.6322 0)
			(size 0.762 0.762)
			(drill 0.5588)
			(layers "*.Cu" "*.Mask")
			(remove_unused_layers no)
			(net "GND")
			(clearance 0.1524)
			(thermal_gap 0.1524)
		)
		(pad "3" thru_hole circle
			(at 2.568448 -2.568448)
			(size 0.762 0.762)
			(drill 0.5588)
			(layers "*.Cu" "*.Mask")
			(remove_unused_layers no)
			(net "GND")
			(clearance 0.1524)
			(thermal_gap 0.1524)
		)
		(pad "4" thru_hole circle
			(at 0 -3.6322)
			(size 0.762 0.762)
			(drill 0.5588)
			(layers "*.Cu" "*.Mask")
			(remove_unused_layers no)
			(net "GND")
			(clearance 0.1524)
			(thermal_gap 0.1524)
		)
		(pad "5" thru_hole circle
			(at -2.568448 -2.568448)
			(size 0.762 0.762)
			(drill 0.5588)
			(layers "*.Cu" "*.Mask")
			(remove_unused_layers no)
			(net "GND")
			(clearance 0.1524)
			(thermal_gap 0.1524)
		)
		(pad "6" thru_hole circle
			(at -3.6322 0)
			(size 0.762 0.762)
			(drill 0.5588)
			(layers "*.Cu" "*.Mask")
			(remove_unused_layers no)
			(net "GND")
			(clearance 0.1524)
			(thermal_gap 0.1524)
		)
		(pad "7" thru_hole circle
			(at -2.568448 2.568448)
			(size 0.762 0.762)
			(drill 0.5588)
			(layers "*.Cu" "*.Mask")
			(remove_unused_layers no)
			(net "GND")
			(clearance 0.1524)
			(thermal_gap 0.1524)
		)
		(pad "8" thru_hole circle
			(at 0 3.6322)
			(size 0.762 0.762)
			(drill 0.5588)
			(layers "*.Cu" "*.Mask")
			(remove_unused_layers no)
			(net "GND")
			(clearance 0.1524)
			(thermal_gap 0.1524)
		)
		(pad "9" thru_hole circle
			(at 2.568448 2.568448)
			(size 0.762 0.762)
			(drill 0.5588)
			(layers "*.Cu" "*.Mask")
			(remove_unused_layers no)
			(net "GND")
			(clearance 0.1524)
			(thermal_gap 0.1524)
		)
		(zone
			(layer "F.Cu")
			(hatch none 0.5)
			(connect_pads
				(clearance 0)
			)
			(min_thickness 0.25)
			(keepout
				(tracks not_allowed)
				(vias allowed)
				(pads allowed)
				(copperpour not_allowed)
				(footprints allowed)
			)
			(placement
				(enabled no)
				(sheetname "")
			)
			(fill
				(thermal_gap 0.5)
				(thermal_bridge_width 0.5)
				(island_removal_mode 0)
			)
			(polygon
				(pts
					(arc
						(start 377.949714 -262.899906)
						(mid 369.94973 -270.89989)
						(end 377.949714 -278.899874)
					)
					(arc
						(start 377.949714 -275.64969)
						(mid 373.199914 -270.89989)
						(end 377.949714 -266.15009)
					)
				)
			)
		)
		(zone
			(layer "F.Cu")
			(hatch none 0.5)
			(connect_pads
				(clearance 0)
			)
			(min_thickness 0.25)
			(keepout
				(tracks not_allowed)
				(vias allowed)
				(pads allowed)
				(copperpour not_allowed)
				(footprints allowed)
			)
			(placement
				(enabled no)
				(sheetname "")
			)
			(fill
				(thermal_gap 0.5)
				(thermal_bridge_width 0.5)
				(island_removal_mode 0)
			)
			(polygon
				(pts
					(arc
						(start 377.949714 -262.899906)
						(mid 385.949698 -270.89989)
						(end 377.949714 -278.899874)
					)
					(arc
						(start 377.949714 -275.64969)
						(mid 382.699514 -270.89989)
						(end 377.949714 -266.15009)
					)
				)
			)
		)
		(zone
			(layers "F.Cu" "B.Cu" "In1.Cu" "In2.Cu" "In3.Cu" "In4.Cu" "In5.Cu" "In6.Cu"
				"In7.Cu" "In8.Cu" "In9.Cu" "In10.Cu" "In11.Cu" "In12.Cu" "In13.Cu" "In14.Cu"
				"In15.Cu" "In16.Cu"
			)
			(hatch none 0.5)
			(connect_pads
				(clearance 0)
			)
			(min_thickness 0.25)
			(keepout
				(tracks not_allowed)
				(vias allowed)
				(pads allowed)
				(copperpour not_allowed)
				(footprints allowed)
			)
			(placement
				(enabled no)
				(sheetname "")
			)
			(fill
				(thermal_gap 0.5)
				(thermal_bridge_width 0.5)
				(island_removal_mode 0)
			)
			(polygon
				(pts
					(arc
						(start 380.715774 -270.89989)
						(mid 375.183654 -270.89989)
						(end 380.715774 -270.89989)
					)
				)
			)
		)
		(zone
			(layer "B.Cu")
			(hatch none 0.5)
			(connect_pads
				(clearance 0)
			)
			(min_thickness 0.25)
			(keepout
				(tracks not_allowed)
				(vias allowed)
				(pads allowed)
				(copperpour not_allowed)
				(footprints allowed)
			)
			(placement
				(enabled no)
				(sheetname "")
			)
			(fill
				(thermal_gap 0.5)
				(thermal_bridge_width 0.5)
				(island_removal_mode 0)
			)
			(polygon
				(pts
					(arc
						(start 377.949714 -265.89609)
						(mid 372.945914 -270.89989)
						(end 377.949714 -275.90369)
					)
					(arc
						(start 377.949714 -275.42109)
						(mid 373.428514 -270.89989)
						(end 377.949714 -266.37869)
					)
				)
			)
		)
		(zone
			(layer "B.Cu")
			(hatch none 0.5)
			(connect_pads
				(clearance 0)
			)
			(min_thickness 0.25)
			(keepout
				(tracks not_allowed)
				(vias allowed)
				(pads allowed)
				(copperpour not_allowed)
				(footprints allowed)
			)
			(placement
				(enabled no)
				(sheetname "")
			)
			(fill
				(thermal_gap 0.5)
				(thermal_bridge_width 0.5)
				(island_removal_mode 0)
			)
			(polygon
				(pts
					(arc
						(start 377.949714 -265.89609)
						(mid 382.953514 -270.89989)
						(end 377.949714 -275.90369)
					)
					(arc
						(start 377.949714 -275.42109)
						(mid 382.470914 -270.89989)
						(end 377.949714 -266.37869)
					)
				)
			)
		)
	)
	(footprint ""
		(layer "F.Cu")
		(at 203.106782 -294.77335 90)
		(property "Reference" "U426"
			(at -1.0922 -2.174748 90)
			(unlocked yes)
			(layer "F.SilkS")
			(effects
				(font
					(size 0.7874 0.5842)
					(thickness 0.1524)
				)
				(justify left)
			)
		)
		(property "Value" ""
			(at 0 0 90)
			(layer "F.Fab")
			(effects
				(font
					(size 1.27 1.27)
				)
			)
		)
		(duplicate_pad_numbers_are_jumpers no)
		(fp_line
			(start 1.0414 -1.575054)
			(end 1.0414 1.575054)
			(stroke
				(width 0.1524)
				(type default)
			)
			(layer "F.SilkS")
		)
		(fp_line
			(start 0.254 -1.575054)
			(end 1.0414 -1.575054)
			(stroke
				(width 0.1524)
				(type default)
			)
			(layer "F.SilkS")
		)
		(fp_line
			(start 0.2286 -1.575054)
			(end 0 -1.272032)
			(stroke
				(width 0.1524)
				(type default)
			)
			(layer "F.SilkS")
		)
		(fp_line
			(start -1.0414 -1.575054)
			(end -0.254 -1.575054)
			(stroke
				(width 0.1524)
				(type default)
			)
			(layer "F.SilkS")
		)
		(fp_line
			(start 0 -1.272032)
			(end -0.254 -1.575054)
			(stroke
				(width 0.1524)
				(type default)
			)
			(layer "F.SilkS")
		)
		(fp_line
			(start 1.0414 1.575054)
			(end -1.0414 1.575054)
			(stroke
				(width 0.1524)
				(type default)
			)
			(layer "F.SilkS")
		)
		(fp_line
			(start -1.0414 1.575054)
			(end -1.0414 -1.575054)
			(stroke
				(width 0.1524)
				(type default)
			)
			(layer "F.SilkS")
		)
		(fp_poly
			(pts
				(xy -2.710688 -0.975106) (xy -3.726688 -1.483106) (xy -3.726688 -0.467106)
			)
			(stroke
				(width 0)
				(type default)
			)
			(fill yes)
			(layer "F.SilkS")
		)
		(fp_line
			(start 1.4478 -1.5748)
			(end 1.4478 -1.2192)
			(stroke
				(width 0.1)
				(type default)
			)
			(layer "F.Fab")
		)
		(fp_line
			(start -1.4478 -1.5748)
			(end 1.4478 -1.5748)
			(stroke
				(width 0.1)
				(type default)
			)
			(layer "F.Fab")
		)
		(fp_line
			(start 2.5654 -1.2192)
			(end 2.5654 1.2192)
			(stroke
				(width 0.1)
				(type default)
			)
			(layer "F.Fab")
		)
		(fp_line
			(start 1.4478 -1.2192)
			(end 2.5654 -1.2192)
			(stroke
				(width 0.1)
				(type default)
			)
			(layer "F.Fab")
		)
		(fp_line
			(start -1.4478 -1.2192)
			(end -1.4478 -1.5748)
			(stroke
				(width 0.1)
				(type default)
			)
			(layer "F.Fab")
		)
		(fp_line
			(start -2.5654 -1.2192)
			(end -1.4478 -1.2192)
			(stroke
				(width 0.1)
				(type default)
			)
			(layer "F.Fab")
		)
		(fp_line
			(start 2.5654 1.2192)
			(end 1.4478 1.2192)
			(stroke
				(width 0.1)
				(type default)
			)
			(layer "F.Fab")
		)
		(fp_line
			(start 1.4478 1.2192)
			(end 1.4478 1.5748)
			(stroke
				(width 0.1)
				(type default)
			)
			(layer "F.Fab")
		)
		(fp_line
			(start -1.4478 1.2192)
			(end -2.5654 1.2192)
			(stroke
				(width 0.1)
				(type default)
			)
			(layer "F.Fab")
		)
		(fp_line
			(start -2.5654 1.2192)
			(end -2.5654 -1.2192)
			(stroke
				(width 0.1)
				(type default)
			)
			(layer "F.Fab")
		)
		(fp_line
			(start 1.4478 1.5748)
			(end -1.4478 1.5748)
			(stroke
				(width 0.1)
				(type default)
			)
			(layer "F.Fab")
		)
		(fp_line
			(start -1.4478 1.5748)
			(end -1.4478 1.2192)
			(stroke
				(width 0.1)
				(type default)
			)
			(layer "F.Fab")
		)
		(fp_poly
			(pts
				(xy -2.710688 -0.975106) (xy -3.726688 -1.483106) (xy -3.726688 -0.467106)
			)
			(stroke
				(width 0)
				(type default)
			)
			(fill yes)
			(layer "F.Fab")
		)
		(pad "1" smd rect
			(at -1.849882 -0.975106)
			(size 0.3556 1.3208)
			(layers "F.Cu" "F.Mask" "F.Paste")
			(net "RST_PEX1_PERST_R_N")
		)
		(pad "2" smd rect
			(at -1.849882 -0.32512)
			(size 0.3556 1.3208)
			(layers "F.Cu" "F.Mask" "F.Paste")
			(net "RST_PEX1_S0_PERST_N")
		)
		(pad "3" smd rect
			(at -1.849882 0.32512)
			(size 0.3556 1.3208)
			(layers "F.Cu" "F.Mask" "F.Paste")
			(net "RST_PEX1_PERST_R_N")
		)
		(pad "4" smd rect
			(at -1.849882 0.975106)
			(size 0.3556 1.3208)
			(layers "F.Cu" "F.Mask" "F.Paste")
			(net "GND")
		)
		(pad "5" smd rect
			(at 1.849882 0.975106)
			(size 0.3556 1.3208)
			(layers "F.Cu" "F.Mask" "F.Paste")
			(net "RST_PEX1_S1_PERST_N")
		)
		(pad "6" smd rect
			(at 1.849882 0.32512)
			(size 0.3556 1.3208)
			(layers "F.Cu" "F.Mask" "F.Paste")
			(net "RST_PEX1_PERST_R_N")
		)
		(pad "7" smd rect
			(at 1.849882 -0.32512)
			(size 0.3556 1.3208)
			(layers "F.Cu" "F.Mask" "F.Paste")
			(net "RST_PEX1_S3_PERST_N")
		)
		(pad "8" smd rect
			(at 1.849882 -0.975106)
			(size 0.3556 1.3208)
			(layers "F.Cu" "F.Mask" "F.Paste")
			(net "P1V8_PEX")
		)
	)
	(footprint ""
		(layer "F.Cu")
		(at 258.659376 -22.955504 90)
		(property "Reference" "R1699"
			(at 0 0 90)
			(layer "F.SilkS")
			(hide yes)
			(effects
				(font
					(size 1.27 1.27)
				)
			)
		)
		(property "Value" ""
			(at 0 0 90)
			(layer "F.Fab")
			(effects
				(font
					(size 1.27 1.27)
				)
			)
		)
		(duplicate_pad_numbers_are_jumpers no)
		(fp_line
			(start 0.7874 -0.4064)
			(end 0.7874 0.4064)
			(stroke
				(width 0.1524)
				(type default)
			)
			(layer "F.SilkS")
		)
		(fp_line
			(start -0.7874 -0.4064)
			(end 0.7874 -0.4064)
			(stroke
				(width 0.1524)
				(type default)
			)
			(layer "F.SilkS")
		)
		(fp_line
			(start 0.7874 0.4064)
			(end -0.7874 0.4064)
			(stroke
				(width 0.1524)
				(type default)
			)
			(layer "F.SilkS")
		)
		(fp_line
			(start -0.7874 0.4064)
			(end -0.7874 -0.4064)
			(stroke
				(width 0.1524)
				(type default)
			)
			(layer "F.SilkS")
		)
		(fp_line
			(start -0.12065 -0.305054)
			(end -0.12065 -0.2794)
			(stroke
				(width 0.1)
				(type default)
			)
			(layer "F.Fab")
		)
		(fp_line
			(start -0.67945 -0.305054)
			(end -0.12065 -0.305054)
			(stroke
				(width 0.1)
				(type default)
			)
			(layer "F.Fab")
		)
		(fp_line
			(start 0.67945 -0.3048)
			(end 0.67945 0.3048)
			(stroke
				(width 0.1)
				(type default)
			)
			(layer "F.Fab")
		)
		(fp_line
			(start 0.12065 -0.3048)
			(end 0.67945 -0.3048)
			(stroke
				(width 0.1)
				(type default)
			)
			(layer "F.Fab")
		)
		(fp_line
			(start 0.12065 -0.2794)
			(end 0.12065 -0.3048)
			(stroke
				(width 0.1)
				(type default)
			)
			(layer "F.Fab")
		)
		(fp_line
			(start -0.12065 -0.2794)
			(end 0.12065 -0.2794)
			(stroke
				(width 0.1)
				(type default)
			)
			(layer "F.Fab")
		)
		(fp_line
			(start 0.120396 0.2794)
			(end -0.12065 0.2794)
			(stroke
				(width 0.1)
				(type default)
			)
			(layer "F.Fab")
		)
		(fp_line
			(start -0.12065 0.2794)
			(end -0.12065 0.3048)
			(stroke
				(width 0.1)
				(type default)
			)
			(layer "F.Fab")
		)
		(fp_line
			(start 0.67945 0.3048)
			(end 0.120396 0.3048)
			(stroke
				(width 0.1)
				(type default)
			)
			(layer "F.Fab")
		)
		(fp_line
			(start 0.120396 0.3048)
			(end 0.120396 0.2794)
			(stroke
				(width 0.1)
				(type default)
			)
			(layer "F.Fab")
		)
		(fp_line
			(start -0.12065 0.3048)
			(end -0.67945 0.3048)
			(stroke
				(width 0.1)
				(type default)
			)
			(layer "F.Fab")
		)
		(fp_line
			(start -0.67945 0.3048)
			(end -0.67945 -0.305054)
			(stroke
				(width 0.1)
				(type default)
			)
			(layer "F.Fab")
		)
		(pad "1" smd circle
			(at -0.40005 0 90)
			(size 0 0)
			(layers "F.Cu" "F.Mask" "F.Paste")
			(net "SMB_BIC_I2C9_MUX1_SSD8_R_SCL")
		)
		(pad "2" smd circle
			(at 0.40005 0 90)
			(size 0 0)
			(layers "F.Cu" "F.Mask" "F.Paste")
			(net "SMB_ISO_SSD8_SCL")
		)
	)
	(footprint ""
		(layer "F.Cu")
		(at 431.95621 -61.487812 180)
		(property "Reference" "R6023"
			(at 0 0 180)
			(layer "F.SilkS")
			(hide yes)
			(effects
				(font
					(size 1.27 1.27)
				)
			)
		)
		(property "Value" ""
			(at 0 0 180)
			(layer "F.Fab")
			(effects
				(font
					(size 1.27 1.27)
				)
			)
		)
		(duplicate_pad_numbers_are_jumpers no)
		(fp_line
			(start 0.7874 0.4064)
			(end -0.7874 0.4064)
			(stroke
				(width 0.1524)
				(type default)
			)
			(layer "F.SilkS")
		)
		(fp_line
			(start 0.7874 -0.4064)
			(end 0.7874 0.4064)
			(stroke
				(width 0.1524)
				(type default)
			)
			(layer "F.SilkS")
		)
		(fp_line
			(start -0.7874 0.4064)
			(end -0.7874 -0.4064)
			(stroke
				(width 0.1524)
				(type default)
			)
			(layer "F.SilkS")
		)
		(fp_line
			(start -0.7874 -0.4064)
			(end 0.7874 -0.4064)
			(stroke
				(width 0.1524)
				(type default)
			)
			(layer "F.SilkS")
		)
		(fp_line
			(start 0.67945 0.3048)
			(end 0.120396 0.3048)
			(stroke
				(width 0.1)
				(type default)
			)
			(layer "F.Fab")
		)
		(fp_line
			(start 0.67945 -0.3048)
			(end 0.67945 0.3048)
			(stroke
				(width 0.1)
				(type default)
			)
			(layer "F.Fab")
		)
		(fp_line
			(start 0.12065 -0.2794)
			(end 0.12065 -0.3048)
			(stroke
				(width 0.1)
				(type default)
			)
			(layer "F.Fab")
		)
		(fp_line
			(start 0.12065 -0.3048)
			(end 0.67945 -0.3048)
			(stroke
				(width 0.1)
				(type default)
			)
			(layer "F.Fab")
		)
		(fp_line
			(start 0.120396 0.3048)
			(end 0.120396 0.2794)
			(stroke
				(width 0.1)
				(type default)
			)
			(layer "F.Fab")
		)
		(fp_line
			(start 0.120396 0.2794)
			(end -0.12065 0.2794)
			(stroke
				(width 0.1)
				(type default)
			)
			(layer "F.Fab")
		)
		(fp_line
			(start -0.12065 0.3048)
			(end -0.67945 0.3048)
			(stroke
				(width 0.1)
				(type default)
			)
			(layer "F.Fab")
		)
		(fp_line
			(start -0.12065 0.2794)
			(end -0.12065 0.3048)
			(stroke
				(width 0.1)
				(type default)
			)
			(layer "F.Fab")
		)
		(fp_line
			(start -0.12065 -0.2794)
			(end 0.12065 -0.2794)
			(stroke
				(width 0.1)
				(type default)
			)
			(layer "F.Fab")
		)
		(fp_line
			(start -0.12065 -0.305054)
			(end -0.12065 -0.2794)
			(stroke
				(width 0.1)
				(type default)
			)
			(layer "F.Fab")
		)
		(fp_line
			(start -0.67945 0.3048)
			(end -0.67945 -0.305054)
			(stroke
				(width 0.1)
				(type default)
			)
			(layer "F.Fab")
		)
		(fp_line
			(start -0.67945 -0.305054)
			(end -0.12065 -0.305054)
			(stroke
				(width 0.1)
				(type default)
			)
			(layer "F.Fab")
		)
		(pad "1" smd circle
			(at -0.40005 0 180)
			(size 0 0)
			(layers "F.Cu" "F.Mask" "F.Paste")
			(net "P3V3_AUX")
		)
		(pad "2" smd circle
			(at 0.40005 0 180)
			(size 0 0)
			(layers "F.Cu" "F.Mask" "F.Paste")
			(net "PWRGD_P12V_SSD15_D")
		)
	)
)
